(kicad_pcb
	(version 20241229)
	(generator "pcbnew")
	(generator_version "9.0")
	(general
		(thickness 1.599998)
		(legacy_teardrops no)
	)
	(paper "A4")
	(title_block
		(title "Artix - Datacenter Secure Control Module (DC-SCM)")
		(date "2024-11-06")
		(rev "1.1.3")
		(comment 9 "footprints 198-199 of 544")
	)
	(layers
		(0 "F.Cu" signal)
		(4 "In1.Cu" signal)
		(6 "In2.Cu" signal)
		(8 "In3.Cu" signal)
		(10 "In4.Cu" signal)
		(12 "In5.Cu" signal)
		(14 "In6.Cu" signal)
		(2 "B.Cu" signal)
		(9 "F.Adhes" user "F.Adhesive")
		(11 "B.Adhes" user "B.Adhesive")
		(13 "F.Paste" user)
		(15 "B.Paste" user)
		(5 "F.SilkS" user "F.Silkscreen")
		(7 "B.SilkS" user "B.Silkscreen")
		(1 "F.Mask" user)
		(3 "B.Mask" user)
		(17 "Dwgs.User" user "User.Drawings")
		(19 "Cmts.User" user "User.Comments")
		(21 "Eco1.User" user "User.Eco1")
		(23 "Eco2.User" user "User.Eco2")
		(25 "Edge.Cuts" user)
		(27 "Margin" user)
		(31 "F.CrtYd" user "F.Courtyard")
		(29 "B.CrtYd" user "B.Courtyard")
		(35 "F.Fab" user)
		(33 "B.Fab" user)
	)
	(footprint "antmicro-footprints:USB-Micro-B_Receptacle_Amphenol_10118192"
		(layer "F.Cu")
		(at 126.225 61.655 180)
		(property "Reference" "J3"
			(at 5.025 -4.145 180)
			(layer "F.SilkS")
			(effects
				(font
					(size 0.7 0.7)
					(thickness 0.15)
				)
				(justify left bottom)
			)
		)
		(property "Value" "USB-Micro-B_Amphenol_10118192-0001LF"
			(at 0 4 180)
			(layer "F.Fab")
			(effects
				(font
					(size 0.7 0.7)
					(thickness 0.15)
				)
				(justify left bottom)
			)
		)
		(property "Datasheet" "http://www.amphenol-icc.com/media/wysiwyg/files/drawing/10118192.pdf"
			(at 0 0 180)
			(layer "F.Fab")
			(hide yes)
			(effects
				(font
					(size 1.27 1.27)
					(thickness 0.15)
				)
			)
		)
		(property "Description" "USB - micro B USB 2.0 Receptacle Connector 5 Position Surface Mount, Right Angle"
			(at 0 0 180)
			(layer "F.Fab")
			(hide yes)
			(effects
				(font
					(size 1.27 1.27)
					(thickness 0.15)
				)
			)
		)
		(property "Author" "Antmicro"
			(at 252.45 123.31 0)
			(layer "F.Fab")
			(hide yes)
			(effects
				(font
					(size 1 1)
					(thickness 0.15)
				)
			)
		)
		(property "License" "Apache-2.0"
			(at 252.45 123.31 0)
			(layer "F.Fab")
			(hide yes)
			(effects
				(font
					(size 1 1)
					(thickness 0.15)
				)
			)
		)
		(property "MPN" "10118192-0001LF"
			(at 252.45 123.31 0)
			(layer "F.Fab")
			(hide yes)
			(effects
				(font
					(size 1 1)
					(thickness 0.15)
				)
			)
		)
		(property "Manufacturer" "Amphenol"
			(at 252.45 123.31 0)
			(layer "F.Fab")
			(hide yes)
			(effects
				(font
					(size 1 1)
					(thickness 0.15)
				)
			)
		)
		(property "VSD_class" "USB Micro"
			(at 252.45 123.31 0)
			(layer "F.Fab")
			(hide yes)
			(effects
				(font
					(size 1 1)
					(thickness 0.15)
				)
			)
		)
		(sheetname "/Interfaces/")
		(sheetfile "interfaces.kicad_sch")
		(attr smd)
		(fp_line
			(start 4.049 -1.151)
			(end 4.049 -0.652)
			(stroke
				(width 0.15)
				(type solid)
			)
			(layer "F.SilkS")
		)
		(fp_line
			(start 1.65 -2.902)
			(end 1.949 -2.902)
			(stroke
				(width 0.15)
				(type solid)
			)
			(layer "F.SilkS")
		)
		(fp_line
			(start -1.901 -2.902)
			(end -1.601 -2.902)
			(stroke
				(width 0.15)
				(type solid)
			)
			(layer "F.SilkS")
		)
		(fp_line
			(start -4.05 -1.151)
			(end -4.05 -0.701)
			(stroke
				(width 0.15)
				(type solid)
			)
			(layer "F.SilkS")
		)
		(fp_circle
			(center -1.75 -3.15)
			(end -1.7 -3.15)
			(stroke
				(width 0.15)
				(type solid)
			)
			(fill no)
			(layer "F.SilkS")
		)
		(fp_rect
			(start -4.758 -3.051)
			(end 4.755 3.048)
			(stroke
				(width 0.05)
				(type solid)
			)
			(fill no)
			(layer "F.CrtYd")
		)
		(fp_line
			(start 3.95 2.769)
			(end 3.95 -2.801)
			(stroke
				(width 0.15)
				(type solid)
			)
			(layer "F.Fab")
		)
		(fp_line
			(start 3.95 -2.801)
			(end -3.5 -2.801)
			(stroke
				(width 0.15)
				(type solid)
			)
			(layer "F.Fab")
		)
		(fp_line
			(start -3.951 2.769)
			(end 3.95 2.769)
			(stroke
				(width 0.15)
				(type solid)
			)
			(layer "F.Fab")
		)
		(fp_line
			(start -3.951 -2.351)
			(end -3.5 -2.801)
			(stroke
				(width 0.15)
				(type solid)
			)
			(layer "F.Fab")
		)
		(fp_line
			(start -3.951 -2.351)
			(end -3.951 2.749)
			(stroke
				(width 0.15)
				(type solid)
			)
			(layer "F.Fab")
		)
		(pad "1" smd rect
			(at -1.301 -2.226 180)
			(size 0.4 1.35)
			(layers "F.Cu" "F.Mask" "F.Paste")
			(net 240 "/Interfaces/VBUS")
			(pinfunction "VBUS")
			(pintype "passive")
		)
		(pad "2" smd rect
			(at -0.651 -2.226 180)
			(size 0.4 1.35)
			(layers "F.Cu" "F.Mask" "F.Paste")
			(net 213 "/Interfaces/DBG_USB_D_N")
			(pinfunction "D-")
			(pintype "bidirectional")
		)
		(pad "3" smd rect
			(at 0 -2.226 180)
			(size 0.4 1.35)
			(layers "F.Cu" "F.Mask" "F.Paste")
			(net 212 "/Interfaces/DBG_USB_D_P")
			(pinfunction "D+")
			(pintype "bidirectional")
		)
		(pad "4" smd rect
			(at 0.65 -2.226 180)
			(size 0.4 1.35)
			(layers "F.Cu" "F.Mask" "F.Paste")
			(net 282 "Net-(J3-ID)")
			(pinfunction "ID")
			(pintype "bidirectional")
		)
		(pad "5" smd rect
			(at 1.3 -2.226 180)
			(size 0.4 1.35)
			(layers "F.Cu" "F.Mask" "F.Paste")
			(net 1 "GND")
			(pinfunction "GND")
			(pintype "power_in")
		)
		(pad "SH" smd roundrect
			(at -3.801 0.449 180)
			(size 1.8 1.9)
			(layers "F.Cu" "F.Mask" "F.Paste")
			(roundrect_rratio 0.1)
			(net 1 "GND")
			(pinfunction "SHIELD")
			(pintype "passive")
		)
		(pad "SH" smd roundrect
			(at -3.101 -2.101 180)
			(size 2.1 1.6)
			(layers "F.Cu" "F.Mask" "F.Paste")
			(roundrect_rratio 0.1)
			(net 1 "GND")
			(pinfunction "SHIELD")
			(pintype "passive")
		)
		(pad "SH" smd roundrect
			(at -1.2 0.449 180)
			(size 1.9 1.9)
			(layers "F.Cu" "F.Mask" "F.Paste")
			(roundrect_rratio 0.1)
			(net 1 "GND")
			(pinfunction "SHIELD")
			(pintype "passive")
		)
		(pad "SH" smd roundrect
			(at 1.199 0.449 180)
			(size 1.9 1.9)
			(layers "F.Cu" "F.Mask" "F.Paste")
			(roundrect_rratio 0.1)
			(net 1 "GND")
			(pinfunction "SHIELD")
			(pintype "passive")
		)
		(pad "SH" smd roundrect
			(at 3.1 -2.101 180)
			(size 2.1 1.6)
			(layers "F.Cu" "F.Mask" "F.Paste")
			(roundrect_rratio 0.1)
			(net 1 "GND")
			(pinfunction "SHIELD")
			(pintype "passive")
		)
		(pad "SH" smd roundrect
			(at 3.8 0.449 180)
			(size 1.8 1.9)
			(layers "F.Cu" "F.Mask" "F.Paste")
			(roundrect_rratio 0.1)
			(net 1 "GND")
			(pinfunction "SHIELD")
			(pintype "passive")
		)
	)
	(footprint "antmicro-footprints:PinHeader_2x7_P2mm_Drill0.9mm_878311420"
		(layer "F.Cu")
		(at 142.625 68.555 180)
		(descr "2.00mm Pitch, Milli-Grid PCB Header, Dual Row, Vertical, Through Hole, Shrouded, 14 Circuits, 0.38µm Gold (Au) Plating, with Center Polarization Slot, with Locking Window, without PCB Locator, Tube")
		(tags "PINSTRIP, HEADER ")
		(property "Reference" "J6"
			(at 0 -5.555 180)
			(layer "F.SilkS")
			(effects
				(font
					(size 0.7 0.7)
					(thickness 0.15)
				)
				(justify left bottom)
			)
		)
		(property "Value" "PinHeader_2x7_P2mm_Drill0.9mm_878311420"
			(at 0 3.4 180)
			(layer "F.Fab")
			(effects
				(font
					(size 0.7 0.7)
					(thickness 0.15)
				)
				(justify left bottom)
			)
		)
		(property "Datasheet" "https://www.molex.com/en-us/products/part-detail-pdf/878311420?display=pdf"
			(at 0 0 180)
			(layer "F.Fab")
			(hide yes)
			(effects
				(font
					(size 1.27 1.27)
					(thickness 0.15)
				)
			)
		)
		(property "Description" "2.00mm Pitch, Milli-Grid PCB Header, Dual Row, Vertical, Through Hole, Shrouded, 14 Circuits, 0.38µm Gold (Au) Plating, with Center Polarization Slot, with Locking Window, without PCB Locator, Tube"
			(at 0 0 180)
			(layer "F.Fab")
			(hide yes)
			(effects
				(font
					(size 1.27 1.27)
					(thickness 0.15)
				)
			)
		)
		(property "Author" "Antmicro"
			(at 285.25 137.11 0)
			(layer "F.Fab")
			(hide yes)
			(effects
				(font
					(size 1 1)
					(thickness 0.15)
				)
			)
		)
		(property "License" "Apache-2.0"
			(at 285.25 137.11 0)
			(layer "F.Fab")
			(hide yes)
			(effects
				(font
					(size 1 1)
					(thickness 0.15)
				)
			)
		)
		(property "MPN" "878311420"
			(at 285.25 137.11 0)
			(layer "F.Fab")
			(hide yes)
			(effects
				(font
					(size 1 1)
					(thickness 0.15)
				)
			)
		)
		(property "Manufacturer" "Molex"
			(at 285.25 137.11 0)
			(layer "F.Fab")
			(hide yes)
			(effects
				(font
					(size 1 1)
					(thickness 0.15)
				)
			)
		)
		(sheetname "/Interfaces/")
		(sheetfile "interfaces.kicad_sch")
		(attr through_hole)
		(fp_line
			(start 14.4 2.2)
			(end 7.3 2.2)
			(stroke
				(width 0.15)
				(type solid)
			)
			(layer "F.SilkS")
		)
		(fp_line
			(start 14.4 -4.2)
			(end 14.4 2.2)
			(stroke
				(width 0.15)
				(type solid)
			)
			(layer "F.SilkS")
		)
		(fp_line
			(start -2.4 2.2)
			(end -2.4 -4.2)
			(stroke
				(width 0.15)
				(type solid)
			)
			(layer "F.SilkS")
		)
		(fp_line
			(start -2.4 -4.2)
			(end 14.4 -4.2)
			(stroke
				(width 0.15)
				(type solid)
			)
			(layer "F.SilkS")
		)
		(fp_line
			(start -2.41 2.2)
			(end 4.7 2.2)
			(stroke
				(width 0.15)
				(type solid)
			)
			(layer "F.SilkS")
		)
		(fp_line
			(start 14.51 2.34)
			(end 14.51 -4.34)
			(stroke
				(width 0.05)
				(type solid)
			)
			(layer "F.CrtYd")
		)
		(fp_line
			(start -2.51 2.34)
			(end 14.51 2.34)
			(stroke
				(width 0.05)
				(type solid)
			)
			(layer "F.CrtYd")
		)
		(fp_line
			(start -2.51 2.34)
			(end -2.51 -4.34)
			(stroke
				(width 0.05)
				(type solid)
			)
			(layer "F.CrtYd")
		)
		(fp_line
			(start -2.51 -4.34)
			(end 14.51 -4.34)
			(stroke
				(width 0.05)
				(type solid)
			)
			(layer "F.CrtYd")
		)
		(fp_line
			(start 14.356 2.15)
			(end -2.293 2.15)
			(stroke
				(width 0.15)
				(type solid)
			)
			(layer "F.Fab")
		)
		(fp_line
			(start 14.356 1.898)
			(end 14.356 -4.15)
			(stroke
				(width 0.15)
				(type solid)
			)
			(layer "F.Fab")
		)
		(fp_line
			(start 14.356 -4.15)
			(end -2.32 -4.15)
			(stroke
				(width 0.15)
				(type solid)
			)
			(layer "F.Fab")
		)
		(fp_line
			(start -2.33 2.15)
			(end -2.33 -4.13)
			(stroke
				(width 0.15)
				(type solid)
			)
			(layer "F.Fab")
		)
		(pad "1" thru_hole rect
			(at 0 0)
			(size 1.6 1.6)
			(drill 0.9)
			(layers "*.Cu" "*.Mask")
			(remove_unused_layers no)
			(net 1 "GND")
			(pintype "passive")
		)
		(pad "2" thru_hole circle
			(at 0 -2)
			(size 1.6 1.6)
			(drill 0.9)
			(layers "*.Cu" "*.Mask")
			(remove_unused_layers no)
			(net 2 "VCC3V3")
			(pintype "passive")
		)
		(pad "3" thru_hole circle
			(at 2 0)
			(size 1.6 1.6)
			(drill 0.9)
			(layers "*.Cu" "*.Mask")
			(remove_unused_layers no)
			(net 1 "GND")
			(pintype "passive")
		)
		(pad "4" thru_hole circle
			(at 2 -2)
			(size 1.6 1.6)
			(drill 0.9)
			(layers "*.Cu" "*.Mask")
			(remove_unused_layers no)
			(net 16 "JTAG_TMS")
			(pintype "passive")
		)
		(pad "5" thru_hole circle
			(at 4 0)
			(size 1.6 1.6)
			(drill 0.9)
			(layers "*.Cu" "*.Mask")
			(remove_unused_layers no)
			(net 1 "GND")
			(pintype "passive")
		)
		(pad "6" thru_hole circle
			(at 4 -2)
			(size 1.6 1.6)
			(drill 0.9)
			(layers "*.Cu" "*.Mask")
			(remove_unused_layers no)
			(net 15 "JTAG_TCK")
			(pintype "passive")
		)
		(pad "7" thru_hole circle
			(at 6 0)
			(size 1.6 1.6)
			(drill 0.9)
			(layers "*.Cu" "*.Mask")
			(remove_unused_layers no)
			(net 1 "GND")
			(pintype "passive")
		)
		(pad "8" thru_hole circle
			(at 6 -2)
			(size 1.6 1.6)
			(drill 0.9)
			(layers "*.Cu" "*.Mask")
			(remove_unused_layers no)
			(net 14 "JTAG_TDO")
			(pintype "passive")
		)
		(pad "9" thru_hole circle
			(at 8 0)
			(size 1.6 1.6)
			(drill 0.9)
			(layers "*.Cu" "*.Mask")
			(remove_unused_layers no)
			(net 1 "GND")
			(pintype "passive")
		)
		(pad "10" thru_hole circle
			(at 8 -2)
			(size 1.6 1.6)
			(drill 0.9)
			(layers "*.Cu" "*.Mask")
			(remove_unused_layers no)
			(net 13 "JTAG_TDI")
			(pintype "passive")
		)
		(pad "11" thru_hole circle
			(at 10 0)
			(size 1.6 1.6)
			(drill 0.9)
			(layers "*.Cu" "*.Mask")
			(remove_unused_layers no)
			(net 1 "GND")
			(pintype "passive")
		)
		(pad "12" thru_hole circle
			(at 10 -2)
			(size 1.6 1.6)
			(drill 0.9)
			(layers "*.Cu" "*.Mask")
			(remove_unused_layers no)
			(net 242 "unconnected-(J6-Pad12)")
			(pintype "passive+no_connect")
		)
		(pad "13" thru_hole circle
			(at 12 0)
			(size 1.6 1.6)
			(drill 0.9)
			(layers "*.Cu" "*.Mask")
			(remove_unused_layers no)
			(net 1 "GND")
			(pintype "passive")
		)
		(pad "14" thru_hole circle
			(at 12 -2)
			(size 1.6 1.6)
			(drill 0.9)
			(layers "*.Cu" "*.Mask")
			(remove_unused_layers no)
			(net 241 "unconnected-(J6-Pad14)")
			(pintype "passive+no_connect")
		)
	)
)
